G04 ================== begin FILE IDENTIFICATION RECORD ==================*
G04 Layout Name:  17301-sa.brd*
G04 Film Name:    TSMD*
G04 File Format:  Gerber RS274X*
G04 File Origin:  Cadence Allegro 16.6-2015-S079*
G04 Origin Date:  Thu Jun 22 17:49:55 2017*
G04 *
G04 Layer:  PIN/PASTEMASK_TOP*
G04 Layer:  PACKAGE GEOMETRY/PASTEMASK_TOP*
G04 Layer:  DRAWING FORMAT/LAYER_PAST_T*
G04 Layer:  VIA CLASS/PASTEMASK_TOP*
G04 Layer:  DRAWING FORMAT/LAYER_PCB_STORY*
G04 Layer:  BOARD GEOMETRY/PANEL_OUTLINE*
G04 *
G04 Offset:    (0.00 0.00)*
G04 Mirror:    No*
G04 Mode:      Positive*
G04 Rotation:  0*
G04 FullContactRelief:  No*
G04 UndefLineWidth:     6.00*
G04 ================== end FILE IDENTIFICATION RECORD ====================*
%FSLAX35Y35*MOIN*%
%IR0*IPPOS*OFA0.00000B0.00000*MIA0B0*SFA1.00000B1.00000*%
%AMMACRO16*
4,1,40,.013,.017,
-.013,.017,
-.013695,.016939,
-.014368,.016759,
-.015,.016464,
-.015571,.016064,
-.016064,.015571,
-.016464,.015,
-.016759,.014368,
-.016939,.013695,
-.017,.013,
-.017,-.013,
-.016939,-.013695,
-.016759,-.014368,
-.016464,-.015,
-.016064,-.015571,
-.015571,-.016064,
-.015,-.016464,
-.014368,-.016759,
-.013695,-.016939,
-.013,-.017,
.013,-.017,
.013695,-.016939,
.014368,-.016759,
.015,-.016464,
.015571,-.016064,
.016064,-.015571,
.016464,-.015,
.016759,-.014368,
.016939,-.013695,
.017,-.013,
.017,.013,
.016939,.013695,
.016759,.014368,
.016464,.015,
.016064,.015571,
.015571,.016064,
.015,.016464,
.014368,.016759,
.013695,.016939,
.013,.017,
0.0*
%
%ADD16MACRO16*%
%ADD11C,.04*%
%ADD24C,.028*%
%ADD10C,.086*%
%AMMACRO27*
4,1,40,.011,-.007,
.011,.007,
.010939,.007695,
.010759,.008368,
.010464,.009,
.010064,.009571,
.009571,.010064,
.009,.010464,
.008368,.010759,
.007695,.010939,
.007,.011,
-.007,.011,
-.007695,.010939,
-.008368,.010759,
-.009,.010464,
-.009571,.010064,
-.010064,.009571,
-.010464,.009,
-.010759,.008368,
-.010939,.007695,
-.011,.007,
-.011,-.007,
-.010939,-.007695,
-.010759,-.008368,
-.010464,-.009,
-.010064,-.009571,
-.009571,-.010064,
-.009,-.010464,
-.008368,-.010759,
-.007695,-.010939,
-.007,-.011,
.007,-.011,
.007695,-.010939,
.008368,-.010759,
.009,-.010464,
.009571,-.010064,
.010064,-.009571,
.010464,-.009,
.010759,-.008368,
.010939,-.007695,
.011,-.007,
0.0*
%
%ADD27MACRO27*%
%AMMACRO18*
4,1,40,-.012,.008,
-.012,-.008,
-.011939,-.008695,
-.011759,-.009368,
-.011464,-.01,
-.011064,-.010571,
-.010571,-.011064,
-.01,-.011464,
-.009368,-.011759,
-.008695,-.011939,
-.008,-.012,
.008,-.012,
.008695,-.011939,
.009368,-.011759,
.01,-.011464,
.010571,-.011064,
.011064,-.010571,
.011464,-.01,
.011759,-.009368,
.011939,-.008695,
.012,-.008,
.012,.008,
.011939,.008695,
.011759,.009368,
.011464,.01,
.011064,.010571,
.010571,.011064,
.01,.011464,
.009368,.011759,
.008695,.011939,
.008,.012,
-.008,.012,
-.008695,.011939,
-.009368,.011759,
-.01,.011464,
-.010571,.011064,
-.011064,.010571,
-.011464,.01,
-.011759,.009368,
-.011939,.008695,
-.012,.008,
0.0*
%
%ADD18MACRO18*%
%AMMACRO30*
4,1,40,.008,.012,
-.008,.012,
-.008695,.011939,
-.009368,.011759,
-.01,.011464,
-.010571,.011064,
-.011064,.010571,
-.011464,.01,
-.011759,.009368,
-.011939,.008695,
-.012,.008,
-.012,-.008,
-.011939,-.008695,
-.011759,-.009368,
-.011464,-.01,
-.011064,-.010571,
-.010571,-.011064,
-.01,-.011464,
-.009368,-.011759,
-.008695,-.011939,
-.008,-.012,
.008,-.012,
.008695,-.011939,
.009368,-.011759,
.01,-.011464,
.010571,-.011064,
.011064,-.010571,
.011464,-.01,
.011759,-.009368,
.011939,-.008695,
.012,-.008,
.012,.008,
.011939,.008695,
.011759,.009368,
.011464,.01,
.011064,.010571,
.010571,.011064,
.01,.011464,
.009368,.011759,
.008695,.011939,
.008,.012,
0.0*
%
%ADD30MACRO30*%
%AMMACRO28*
4,1,40,.011,-.007,
.011,.007,
.010939,.007695,
.010759,.008368,
.010464,.009,
.010064,.009571,
.009571,.010064,
.009,.010464,
.008368,.010759,
.007695,.010939,
.007,.011,
-.007,.011,
-.007695,.010939,
-.008368,.010759,
-.009,.010464,
-.009571,.010064,
-.010064,.009571,
-.010464,.009,
-.010759,.008368,
-.010939,.007695,
-.011,.007,
-.011,-.007,
-.010939,-.007695,
-.010759,-.008368,
-.010464,-.009,
-.010064,-.009571,
-.009571,-.010064,
-.009,-.010464,
-.008368,-.010759,
-.007695,-.010939,
-.007,-.011,
.007,-.011,
.007695,-.010939,
.008368,-.010759,
.009,-.010464,
.009571,-.010064,
.010064,-.009571,
.010464,-.009,
.010759,-.008368,
.010939,-.007695,
.011,-.007,
0.0*
%
%ADD28MACRO28*%
%AMMACRO17*
4,1,40,-.012,.008,
-.012,-.008,
-.011939,-.008695,
-.011759,-.009368,
-.011464,-.01,
-.011064,-.010571,
-.010571,-.011064,
-.01,-.011464,
-.009368,-.011759,
-.008695,-.011939,
-.008,-.012,
.008,-.012,
.008695,-.011939,
.009368,-.011759,
.01,-.011464,
.010571,-.011064,
.011064,-.010571,
.011464,-.01,
.011759,-.009368,
.011939,-.008695,
.012,-.008,
.012,.008,
.011939,.008695,
.011759,.009368,
.011464,.01,
.011064,.010571,
.010571,.011064,
.01,.011464,
.009368,.011759,
.008695,.011939,
.008,.012,
-.008,.012,
-.008695,.011939,
-.009368,.011759,
-.01,.011464,
-.010571,.011064,
-.011064,.010571,
-.011464,.01,
-.011759,.009368,
-.011939,.008695,
-.012,.008,
0.0*
%
%ADD17MACRO17*%
%AMMACRO29*
4,1,40,.008,.012,
-.008,.012,
-.008695,.011939,
-.009368,.011759,
-.01,.011464,
-.010571,.011064,
-.011064,.010571,
-.011464,.01,
-.011759,.009368,
-.011939,.008695,
-.012,.008,
-.012,-.008,
-.011939,-.008695,
-.011759,-.009368,
-.011464,-.01,
-.011064,-.010571,
-.010571,-.011064,
-.01,-.011464,
-.009368,-.011759,
-.008695,-.011939,
-.008,-.012,
.008,-.012,
.008695,-.011939,
.009368,-.011759,
.01,-.011464,
.010571,-.011064,
.011064,-.010571,
.011464,-.01,
.011759,-.009368,
.011939,-.008695,
.012,-.008,
.012,.008,
.011939,.008695,
.011759,.009368,
.011464,.01,
.011064,.010571,
.010571,.011064,
.01,.011464,
.009368,.011759,
.008695,.011939,
.008,.012,
0.0*
%
%ADD29MACRO29*%
%ADD23R,.05X.065*%
%ADD15R,.045X.055*%
%AMMACRO25*
4,1,40,-.007,-.011,
.007,-.011,
.007695,-.010939,
.008368,-.010759,
.009,-.010464,
.009571,-.010064,
.010064,-.009571,
.010464,-.009,
.010759,-.008368,
.010939,-.007695,
.011,-.007,
.011,.007,
.010939,.007695,
.010759,.008368,
.010464,.009,
.010064,.009571,
.009571,.010064,
.009,.010464,
.008368,.010759,
.007695,.010939,
.007,.011,
-.007,.011,
-.007695,.010939,
-.008368,.010759,
-.009,.010464,
-.009571,.010064,
-.010064,.009571,
-.010464,.009,
-.010759,.008368,
-.010939,.007695,
-.011,.007,
-.011,-.007,
-.010939,-.007695,
-.010759,-.008368,
-.010464,-.009,
-.010064,-.009571,
-.009571,-.010064,
-.009,-.010464,
-.008368,-.010759,
-.007695,-.010939,
-.007,-.011,
0.0*
%
%ADD25MACRO25*%
%AMMACRO20*
4,1,40,-.008,-.012,
.008,-.012,
.008695,-.011939,
.009368,-.011759,
.01,-.011464,
.010571,-.011064,
.011064,-.010571,
.011464,-.01,
.011759,-.009368,
.011939,-.008695,
.012,-.008,
.012,.008,
.011939,.008695,
.011759,.009368,
.011464,.01,
.011064,.010571,
.010571,.011064,
.01,.011464,
.009368,.011759,
.008695,.011939,
.008,.012,
-.008,.012,
-.008695,.011939,
-.009368,.011759,
-.01,.011464,
-.010571,.011064,
-.011064,.010571,
-.011464,.01,
-.011759,.009368,
-.011939,.008695,
-.012,.008,
-.012,-.008,
-.011939,-.008695,
-.011759,-.009368,
-.011464,-.01,
-.011064,-.010571,
-.010571,-.011064,
-.01,-.011464,
-.009368,-.011759,
-.008695,-.011939,
-.008,-.012,
0.0*
%
%ADD20MACRO20*%
%AMMACRO13*
4,1,40,.012,-.008,
.012,.008,
.011939,.008695,
.011759,.009368,
.011464,.01,
.011064,.010571,
.010571,.011064,
.01,.011464,
.009368,.011759,
.008695,.011939,
.008,.012,
-.008,.012,
-.008695,.011939,
-.009368,.011759,
-.01,.011464,
-.010571,.011064,
-.011064,.010571,
-.011464,.01,
-.011759,.009368,
-.011939,.008695,
-.012,.008,
-.012,-.008,
-.011939,-.008695,
-.011759,-.009368,
-.011464,-.01,
-.011064,-.010571,
-.010571,-.011064,
-.01,-.011464,
-.009368,-.011759,
-.008695,-.011939,
-.008,-.012,
.008,-.012,
.008695,-.011939,
.009368,-.011759,
.01,-.011464,
.010571,-.011064,
.011064,-.010571,
.011464,-.01,
.011759,-.009368,
.011939,-.008695,
.012,-.008,
0.0*
%
%ADD13MACRO13*%
%AMMACRO21*
4,1,40,-.011,.007,
-.011,-.007,
-.010939,-.007695,
-.010759,-.008368,
-.010464,-.009,
-.010064,-.009571,
-.009571,-.010064,
-.009,-.010464,
-.008368,-.010759,
-.007695,-.010939,
-.007,-.011,
.007,-.011,
.007695,-.010939,
.008368,-.010759,
.009,-.010464,
.009571,-.010064,
.010064,-.009571,
.010464,-.009,
.010759,-.008368,
.010939,-.007695,
.011,-.007,
.011,.007,
.010939,.007695,
.010759,.008368,
.010464,.009,
.010064,.009571,
.009571,.010064,
.009,.010464,
.008368,.010759,
.007695,.010939,
.007,.011,
-.007,.011,
-.007695,.010939,
-.008368,.010759,
-.009,.010464,
-.009571,.010064,
-.010064,.009571,
-.010464,.009,
-.010759,.008368,
-.010939,.007695,
-.011,.007,
0.0*
%
%ADD21MACRO21*%
%AMMACRO14*
4,1,40,.013,.017,
-.013,.017,
-.013695,.016939,
-.014368,.016759,
-.015,.016464,
-.015571,.016064,
-.016064,.015571,
-.016464,.015,
-.016759,.014368,
-.016939,.013695,
-.017,.013,
-.017,-.013,
-.016939,-.013695,
-.016759,-.014368,
-.016464,-.015,
-.016064,-.015571,
-.015571,-.016064,
-.015,-.016464,
-.014368,-.016759,
-.013695,-.016939,
-.013,-.017,
.013,-.017,
.013695,-.016939,
.014368,-.016759,
.015,-.016464,
.015571,-.016064,
.016064,-.015571,
.016464,-.015,
.016759,-.014368,
.016939,-.013695,
.017,-.013,
.017,.013,
.016939,.013695,
.016759,.014368,
.016464,.015,
.016064,.015571,
.015571,.016064,
.015,.016464,
.014368,.016759,
.013695,.016939,
.013,.017,
0.0*
%
%ADD14MACRO14*%
%AMMACRO26*
4,1,40,-.007,-.011,
.007,-.011,
.007695,-.010939,
.008368,-.010759,
.009,-.010464,
.009571,-.010064,
.010064,-.009571,
.010464,-.009,
.010759,-.008368,
.010939,-.007695,
.011,-.007,
.011,.007,
.010939,.007695,
.010759,.008368,
.010464,.009,
.010064,.009571,
.009571,.010064,
.009,.010464,
.008368,.010759,
.007695,.010939,
.007,.011,
-.007,.011,
-.007695,.010939,
-.008368,.010759,
-.009,.010464,
-.009571,.010064,
-.010064,.009571,
-.010464,.009,
-.010759,.008368,
-.010939,.007695,
-.011,.007,
-.011,-.007,
-.010939,-.007695,
-.010759,-.008368,
-.010464,-.009,
-.010064,-.009571,
-.009571,-.010064,
-.009,-.010464,
-.008368,-.010759,
-.007695,-.010939,
-.007,-.011,
0.0*
%
%ADD26MACRO26*%
%AMMACRO19*
4,1,40,-.008,-.012,
.008,-.012,
.008695,-.011939,
.009368,-.011759,
.01,-.011464,
.010571,-.011064,
.011064,-.010571,
.011464,-.01,
.011759,-.009368,
.011939,-.008695,
.012,-.008,
.012,.008,
.011939,.008695,
.011759,.009368,
.011464,.01,
.011064,.010571,
.010571,.011064,
.01,.011464,
.009368,.011759,
.008695,.011939,
.008,.012,
-.008,.012,
-.008695,.011939,
-.009368,.011759,
-.01,.011464,
-.010571,.011064,
-.011064,.010571,
-.011464,.01,
-.011759,.009368,
-.011939,.008695,
-.012,.008,
-.012,-.008,
-.011939,-.008695,
-.011759,-.009368,
-.011464,-.01,
-.011064,-.010571,
-.010571,-.011064,
-.01,-.011464,
-.009368,-.011759,
-.008695,-.011939,
-.008,-.012,
0.0*
%
%ADD19MACRO19*%
%AMMACRO12*
4,1,40,.012,-.008,
.012,.008,
.011939,.008695,
.011759,.009368,
.011464,.01,
.011064,.010571,
.010571,.011064,
.01,.011464,
.009368,.011759,
.008695,.011939,
.008,.012,
-.008,.012,
-.008695,.011939,
-.009368,.011759,
-.01,.011464,
-.010571,.011064,
-.011064,.010571,
-.011464,.01,
-.011759,.009368,
-.011939,.008695,
-.012,.008,
-.012,-.008,
-.011939,-.008695,
-.011759,-.009368,
-.011464,-.01,
-.011064,-.010571,
-.010571,-.011064,
-.01,-.011464,
-.009368,-.011759,
-.008695,-.011939,
-.008,-.012,
.008,-.012,
.008695,-.011939,
.009368,-.011759,
.01,-.011464,
.010571,-.011064,
.011064,-.010571,
.011464,-.01,
.011759,-.009368,
.011939,-.008695,
.012,-.008,
0.0*
%
%ADD12MACRO12*%
%AMMACRO22*
4,1,40,-.011,.007,
-.011,-.007,
-.010939,-.007695,
-.010759,-.008368,
-.010464,-.009,
-.010064,-.009571,
-.009571,-.010064,
-.009,-.010464,
-.008368,-.010759,
-.007695,-.010939,
-.007,-.011,
.007,-.011,
.007695,-.010939,
.008368,-.010759,
.009,-.010464,
.009571,-.010064,
.010064,-.009571,
.010464,-.009,
.010759,-.008368,
.010939,-.007695,
.011,-.007,
.011,.007,
.010939,.007695,
.010759,.008368,
.010464,.009,
.010064,.009571,
.009571,.010064,
.009,.010464,
.008368,.010759,
.007695,.010939,
.007,.011,
-.007,.011,
-.007695,.010939,
-.008368,.010759,
-.009,.010464,
-.009571,.010064,
-.010064,.009571,
-.010464,.009,
-.010759,.008368,
-.010939,.007695,
-.011,.007,
0.0*
%
%ADD22MACRO22*%
%ADD31C,.02*%
%ADD32C,.006*%
G75*
%LPD*%
G75*
G54D10*
X-14755Y415558D03*
X-12454Y45507D03*
X29461Y718854D03*
X141466Y655356D03*
X395935Y76695D03*
X508569Y15093D03*
X554126Y315939D03*
Y685624D03*
G54D20*
X207500Y78300D03*
X211100Y35600D03*
X320946Y46429D03*
X324423Y46424D03*
X479900Y227300D03*
X502868Y163086D03*
G54D11*
X20847Y701602D03*
X32739Y30456D03*
X514356Y57612D03*
G54D12*
X48300Y76000D03*
Y79500D03*
X225756Y38299D03*
X221430Y79364D03*
X296700Y164800D03*
X307800Y209500D03*
Y206000D03*
G54D21*
X214956Y32099D03*
X211500Y74800D03*
X320965Y32100D03*
X325152Y32095D03*
X483700Y223800D03*
X506868Y159586D03*
G54D30*
X331151Y150040D03*
X361000Y37700D03*
G54D31*
G01X-139981Y-146685D02*
G02I-12000J0D01*
G01X-145131D02*
G02I-6850J0D01*
G01X-135981D02*
X-167981D01*
G01X-135981Y-162685D02*
Y-242685D01*
G01D02*
X971619D01*
G01X-135981Y-198185D02*
X971619D01*
G01X-151981Y-162685D02*
Y-130685D01*
G01X-135981Y-162685D02*
X971619D01*
G01X184119D02*
Y-242685D01*
G01X321619Y-162685D02*
Y-242685D01*
G01X436619Y-162685D02*
Y-242685D01*
G01X604119Y-162685D02*
Y-242685D01*
G01X774119Y-162685D02*
Y-242685D01*
G01X971619Y-162685D02*
Y-242685D01*
G01X999619Y-146685D02*
G02I-12000J0D01*
G01X1003619D02*
X971619D01*
G01X994469D02*
G02I-6850J0D01*
G01X987619Y-162685D02*
Y-130685D01*
G54D22*
X214956Y35499D03*
X211500Y78200D03*
X320965Y35500D03*
X325152Y35495D03*
X483700Y227200D03*
X506868Y162986D03*
G54D13*
X44700Y76000D03*
Y79500D03*
X222156Y38299D03*
X217830Y79364D03*
X293100Y164800D03*
X304200Y209500D03*
Y206000D03*
G54D32*
G01X-116181Y-215185D02*
Y-232685D01*
G01X-121203Y-215185D02*
X-111159D01*
G01X-103048Y-232685D02*
Y-215185D01*
X-97808D01*
X-96061Y-216060D01*
X-94751Y-218102D01*
X-94314Y-220435D01*
X-94751Y-222768D01*
X-95843Y-224518D01*
X-97808Y-225394D01*
X-103048D01*
G01X-58878Y-216644D02*
X-60188Y-215768D01*
X-61716Y-215185D01*
X-63463D01*
X-65428Y-216060D01*
X-66956Y-217518D01*
X-68048Y-219269D01*
X-68921Y-222185D01*
X-69140Y-224810D01*
X-68703Y-227435D01*
X-68048Y-229185D01*
X-66738Y-230935D01*
X-65209Y-232102D01*
X-63681Y-232685D01*
X-62153D01*
X-60624Y-232102D01*
X-59314Y-231227D01*
X-58222Y-230061D01*
G01X-49893Y-232685D02*
Y-215185D01*
G01Y-223643D02*
X-48801Y-222185D01*
X-47709Y-221310D01*
X-45963Y-221019D01*
X-44653Y-221310D01*
X-43124Y-222477D01*
X-42469Y-224227D01*
Y-232685D01*
G01X-24751D02*
Y-221019D01*
G01Y-223060D02*
X-25624Y-221894D01*
X-26935Y-221310D01*
X-28463Y-221019D01*
X-29991Y-221602D01*
X-31301Y-222768D01*
X-32175Y-224518D01*
X-32611Y-226852D01*
X-32175Y-229185D01*
X-31301Y-230935D01*
X-29991Y-232102D01*
X-28463Y-232685D01*
X-26935Y-232393D01*
X-25624Y-231519D01*
X-24751Y-230352D01*
G01X-14893Y-232685D02*
Y-221019D01*
G01Y-223935D02*
X-14019Y-222477D01*
X-12709Y-221310D01*
X-10963Y-221019D01*
X-9435Y-221310D01*
X-8124Y-222477D01*
X-7469Y-224518D01*
Y-232685D01*
G01X2607D02*
Y-221019D01*
G01Y-223935D02*
X3481Y-222477D01*
X4791Y-221310D01*
X6537Y-221019D01*
X8065Y-221310D01*
X9376Y-222477D01*
X10031Y-224518D01*
Y-232685D01*
G01X20544Y-224810D02*
X27531D01*
X26876Y-222768D01*
X25784Y-221602D01*
X24256Y-221019D01*
X22727Y-221310D01*
X21417Y-222185D01*
X20544Y-224227D01*
X20107Y-225977D01*
Y-227727D01*
X20544Y-229477D01*
X21636Y-231227D01*
X22946Y-232393D01*
X24474Y-232685D01*
X26002Y-232102D01*
X27531Y-230352D01*
G01X41319Y-232685D02*
Y-215185D01*
G01X71734Y-232685D02*
Y-215185D01*
G01X80904D02*
Y-232685D01*
G01Y-223935D02*
X71734D01*
G01X89016Y-232685D02*
Y-215185D01*
X93382D01*
X95129Y-216060D01*
X96439Y-217227D01*
X97531Y-218976D01*
X98404Y-221019D01*
X98622Y-223935D01*
X98404Y-226852D01*
X97531Y-228894D01*
X96439Y-230644D01*
X95129Y-231810D01*
X93382Y-232685D01*
X89016D01*
G01X106516D02*
Y-215185D01*
X110882D01*
X112629Y-216060D01*
X113939Y-217227D01*
X115031Y-218976D01*
X115904Y-221019D01*
X116122Y-223935D01*
X115904Y-226852D01*
X115031Y-228894D01*
X113939Y-230644D01*
X112629Y-231810D01*
X110882Y-232685D01*
X106516D01*
G01X148065Y-223352D02*
X148939Y-222477D01*
X149594Y-221019D01*
X150031Y-218976D01*
X149594Y-217227D01*
X148721Y-216060D01*
X147192Y-215185D01*
X141297D01*
Y-232685D01*
X148502D01*
X150031Y-231519D01*
X150904Y-229768D01*
X151341Y-227727D01*
X150904Y-225685D01*
X149594Y-223935D01*
X148065Y-223352D01*
X141297D01*
G01X159452Y-232685D02*
Y-215185D01*
X164692D01*
X166439Y-216060D01*
X167749Y-218102D01*
X168186Y-220435D01*
X167749Y-222768D01*
X166657Y-224518D01*
X164692Y-225394D01*
X159452D01*
G01X-16858Y-187685D02*
Y-170185D01*
X-11181Y-184768D01*
X-5504Y-170185D01*
Y-187685D01*
G01X6319D02*
X5009Y-187393D01*
X3699Y-186227D01*
X2825Y-184185D01*
X2389Y-181852D01*
X2825Y-179518D01*
X3699Y-177477D01*
X5009Y-176310D01*
X6319Y-176019D01*
X7629Y-176310D01*
X8939Y-177477D01*
X9812Y-179518D01*
X10031Y-181852D01*
X9812Y-184185D01*
X8939Y-186227D01*
X7629Y-187393D01*
X6319Y-187685D01*
G01X27749Y-170185D02*
Y-187685D01*
G01Y-185061D02*
X26876Y-186519D01*
X25565Y-187393D01*
X24037Y-187685D01*
X22291Y-187102D01*
X20981Y-185644D01*
X20107Y-183894D01*
X19889Y-181852D01*
X20107Y-179810D01*
X20981Y-178060D01*
X22291Y-176602D01*
X24037Y-176019D01*
X25565Y-176310D01*
X26657Y-176894D01*
X27749Y-178060D01*
G01X38044Y-179810D02*
X45031D01*
X44376Y-177768D01*
X43284Y-176602D01*
X41756Y-176019D01*
X40227Y-176310D01*
X38917Y-177185D01*
X38044Y-179227D01*
X37607Y-180977D01*
Y-182727D01*
X38044Y-184477D01*
X39136Y-186227D01*
X40446Y-187393D01*
X41974Y-187685D01*
X43502Y-187102D01*
X45031Y-185352D01*
G01X58819Y-187685D02*
Y-170185D01*
G01X204702Y-187685D02*
Y-170185D01*
X209942D01*
X211689Y-171060D01*
X212999Y-173102D01*
X213436Y-175435D01*
X212999Y-177768D01*
X211907Y-179518D01*
X209942Y-180394D01*
X204702D01*
G01X231372Y-171644D02*
X230062Y-170768D01*
X228534Y-170185D01*
X226787D01*
X224822Y-171060D01*
X223294Y-172518D01*
X222202Y-174269D01*
X221329Y-177185D01*
X221110Y-179810D01*
X221547Y-182435D01*
X222202Y-184185D01*
X223512Y-185935D01*
X225041Y-187102D01*
X226569Y-187685D01*
X228097D01*
X229626Y-187102D01*
X230936Y-186227D01*
X232028Y-185061D01*
G01X245815Y-178352D02*
X246689Y-177477D01*
X247344Y-176019D01*
X247781Y-173976D01*
X247344Y-172227D01*
X246471Y-171060D01*
X244942Y-170185D01*
X239047D01*
Y-187685D01*
X246252D01*
X247781Y-186519D01*
X248654Y-184768D01*
X249091Y-182727D01*
X248654Y-180685D01*
X247344Y-178935D01*
X245815Y-178352D01*
X239047D01*
G01X255019Y-193518D02*
X268119D01*
G01X274047Y-187685D02*
Y-170185D01*
X284091Y-187685D01*
Y-170185D01*
G01X296569Y-187685D02*
X294822Y-187393D01*
X293294Y-186227D01*
X291984Y-184477D01*
X291110Y-182435D01*
X290674Y-180102D01*
Y-177768D01*
X291110Y-175435D01*
X291984Y-173393D01*
X293294Y-171644D01*
X294822Y-170477D01*
X296569Y-170185D01*
X298315Y-170477D01*
X299844Y-171644D01*
X301154Y-173393D01*
X302028Y-175435D01*
X302464Y-177768D01*
Y-180102D01*
X302028Y-182435D01*
X301154Y-184477D01*
X299844Y-186227D01*
X298315Y-187393D01*
X296569Y-187685D01*
G01X217819Y-232685D02*
Y-215185D01*
X215199Y-218685D01*
G01Y-232685D02*
X220439D01*
G01X234882D02*
X235319Y-228894D01*
X235974Y-225685D01*
X236847Y-222768D01*
X237939Y-219560D01*
X239686Y-215185D01*
X230952D01*
G01X248016Y-229185D02*
X249325Y-231227D01*
X251072Y-232393D01*
X253037Y-232685D01*
X254784Y-232393D01*
X256531Y-230935D01*
X257622Y-229185D01*
X257841Y-227435D01*
X257404Y-225394D01*
X255876Y-223935D01*
X254347Y-223352D01*
X252382D01*
G01X254347D02*
X255657Y-222477D01*
X256749Y-221019D01*
X257186Y-219269D01*
X256749Y-217518D01*
X255657Y-216060D01*
X253692Y-215185D01*
X251727Y-215477D01*
X249762Y-216644D01*
G01X270319Y-215185D02*
X268572Y-215768D01*
X267262Y-217227D01*
X266389Y-218976D01*
X265734Y-221310D01*
X265516Y-223935D01*
X265734Y-226560D01*
X266389Y-228894D01*
X267262Y-230644D01*
X268572Y-232102D01*
X270319Y-232685D01*
X272065Y-232102D01*
X273376Y-230644D01*
X274249Y-228894D01*
X274904Y-226560D01*
X275122Y-223935D01*
X274904Y-221310D01*
X274249Y-218976D01*
X273376Y-217227D01*
X272065Y-215768D01*
X270319Y-215185D01*
G01X287819Y-232685D02*
Y-215185D01*
X285199Y-218685D01*
G01Y-232685D02*
X290439D01*
G01X365784Y-230352D02*
X367531Y-231810D01*
X369496Y-232685D01*
X371242D01*
X372989Y-231810D01*
X374299Y-230352D01*
X374954Y-228310D01*
X374517Y-226269D01*
X373426Y-224518D01*
X371461Y-223352D01*
X368841Y-222768D01*
X367312Y-221602D01*
X366657Y-219560D01*
X367094Y-217518D01*
X368186Y-216060D01*
X369714Y-215185D01*
X371242D01*
X372771Y-215768D01*
X374081Y-217227D01*
G01X382410Y-232685D02*
X387869Y-215185D01*
X393328Y-232685D01*
G01X391362Y-226560D02*
X384375D01*
G01X347410Y-170185D02*
X352869Y-187685D01*
X358328Y-170185D01*
G01X374736Y-187685D02*
X366002D01*
Y-170185D01*
X374736D01*
G01X371242Y-178643D02*
X366002D01*
G01X383502Y-187685D02*
Y-170185D01*
X388961D01*
X390707Y-171060D01*
X391799Y-172227D01*
X392236Y-174560D01*
X391799Y-176894D01*
X390489Y-178352D01*
X388961Y-179227D01*
X383502D01*
G01X388961D02*
X392236Y-187685D01*
G01X405369Y-188268D02*
X404932Y-187977D01*
Y-187393D01*
X405369Y-187102D01*
X405806Y-187393D01*
Y-187977D01*
X405369Y-188268D01*
G01X480952Y-170185D02*
Y-187685D01*
X489686D01*
G01X506749D02*
Y-176019D01*
G01Y-178060D02*
X505876Y-176894D01*
X504565Y-176310D01*
X503037Y-176019D01*
X501509Y-176602D01*
X500199Y-177768D01*
X499325Y-179518D01*
X498889Y-181852D01*
X499325Y-184185D01*
X500199Y-185935D01*
X501509Y-187102D01*
X503037Y-187685D01*
X504565Y-187393D01*
X505876Y-186519D01*
X506749Y-185352D01*
G01X515734Y-192935D02*
X517044Y-193518D01*
X518791Y-192935D01*
X519882Y-191769D01*
X520756Y-190310D01*
X522065Y-185644D01*
X524904Y-176019D01*
G01X517917D02*
X522065Y-185644D01*
G01X534544Y-179810D02*
X541531D01*
X540876Y-177768D01*
X539784Y-176602D01*
X538256Y-176019D01*
X536727Y-176310D01*
X535417Y-177185D01*
X534544Y-179227D01*
X534107Y-180977D01*
Y-182727D01*
X534544Y-184477D01*
X535636Y-186227D01*
X536946Y-187393D01*
X538474Y-187685D01*
X540002Y-187102D01*
X541531Y-185352D01*
G01X552262Y-187685D02*
Y-176019D01*
G01Y-178352D02*
X553354Y-177185D01*
X554446Y-176310D01*
X555974Y-176019D01*
X557065Y-176310D01*
X558376Y-177185D01*
G01X494069Y-215185D02*
Y-232685D01*
G01X489047Y-215185D02*
X499091D01*
G01X506984Y-230352D02*
X508731Y-231810D01*
X510696Y-232685D01*
X512442D01*
X514189Y-231810D01*
X515499Y-230352D01*
X516154Y-228310D01*
X515717Y-226269D01*
X514626Y-224518D01*
X512661Y-223352D01*
X510041Y-222768D01*
X508512Y-221602D01*
X507857Y-219560D01*
X508294Y-217518D01*
X509386Y-216060D01*
X510914Y-215185D01*
X512442D01*
X513971Y-215768D01*
X515281Y-217227D01*
G01X523392Y-232685D02*
Y-215185D01*
X529069Y-229768D01*
X534746Y-215185D01*
Y-232685D01*
G01X541766D02*
Y-215185D01*
X546132D01*
X547879Y-216060D01*
X549189Y-217227D01*
X550281Y-218976D01*
X551154Y-221019D01*
X551372Y-223935D01*
X551154Y-226852D01*
X550281Y-228894D01*
X549189Y-230644D01*
X547879Y-231810D01*
X546132Y-232685D01*
X541766D01*
G01X623066Y-187685D02*
Y-170185D01*
X627432D01*
X629179Y-171060D01*
X630489Y-172227D01*
X631581Y-173976D01*
X632454Y-176019D01*
X632672Y-178935D01*
X632454Y-181852D01*
X631581Y-183894D01*
X630489Y-185644D01*
X629179Y-186810D01*
X627432Y-187685D01*
X623066D01*
G01X642094Y-179810D02*
X649081D01*
X648426Y-177768D01*
X647334Y-176602D01*
X645806Y-176019D01*
X644277Y-176310D01*
X642967Y-177185D01*
X642094Y-179227D01*
X641657Y-180977D01*
Y-182727D01*
X642094Y-184477D01*
X643186Y-186227D01*
X644496Y-187393D01*
X646024Y-187685D01*
X647552Y-187102D01*
X649081Y-185352D01*
G01X659594Y-185644D02*
X660686Y-186810D01*
X662214Y-187685D01*
X663524D01*
X664834Y-187102D01*
X665707Y-186227D01*
X666144Y-185061D01*
X665926Y-183310D01*
X665052Y-182435D01*
X661122Y-180685D01*
X660249Y-178643D01*
X660686Y-177185D01*
X661559Y-176310D01*
X662869Y-176019D01*
X664179Y-176310D01*
X665489Y-177185D01*
G01X680369Y-176019D02*
Y-187685D01*
G01Y-171352D02*
X679932Y-171060D01*
Y-170477D01*
X680369Y-170185D01*
X680806Y-170477D01*
Y-171060D01*
X680369Y-171352D01*
G01X694812Y-192060D02*
X696341Y-193227D01*
X698087Y-193518D01*
X699615Y-193227D01*
X700926Y-191769D01*
X701799Y-189727D01*
Y-176019D01*
G01Y-178352D02*
X700926Y-177185D01*
X699615Y-176310D01*
X698087Y-176019D01*
X696341Y-176602D01*
X695249Y-177768D01*
X694375Y-179810D01*
X693939Y-181852D01*
X694157Y-183602D01*
X695031Y-185644D01*
X696341Y-187102D01*
X698087Y-187685D01*
X699397Y-187393D01*
X700926Y-186227D01*
X701799Y-185061D01*
G01X711657Y-187685D02*
Y-176019D01*
G01Y-178935D02*
X712531Y-177477D01*
X713841Y-176310D01*
X715587Y-176019D01*
X717115Y-176310D01*
X718426Y-177477D01*
X719081Y-179518D01*
Y-187685D01*
G01X729594Y-179810D02*
X736581D01*
X735926Y-177768D01*
X734834Y-176602D01*
X733306Y-176019D01*
X731777Y-176310D01*
X730467Y-177185D01*
X729594Y-179227D01*
X729157Y-180977D01*
Y-182727D01*
X729594Y-184477D01*
X730686Y-186227D01*
X731996Y-187393D01*
X733524Y-187685D01*
X735052Y-187102D01*
X736581Y-185352D01*
G01X747312Y-187685D02*
Y-176019D01*
G01Y-178352D02*
X748404Y-177185D01*
X749496Y-176310D01*
X751024Y-176019D01*
X752115Y-176310D01*
X753426Y-177185D01*
G01X664179Y-223935D02*
X668546D01*
Y-229185D01*
X667236Y-230935D01*
X665707Y-232102D01*
X663524Y-232685D01*
X661341Y-232102D01*
X659812Y-230935D01*
X658502Y-229185D01*
X657629Y-227143D01*
X657192Y-224810D01*
Y-222768D01*
X657629Y-221019D01*
X658502Y-218976D01*
X659812Y-217227D01*
X661122Y-216060D01*
X662869Y-215185D01*
X664397D01*
X666144Y-215768D01*
X667454Y-216935D01*
G01X684736Y-232685D02*
X676002D01*
Y-215185D01*
X684736D01*
G01X681242Y-223643D02*
X676002D01*
G01X693502Y-215185D02*
Y-232685D01*
X702236D01*
G01X715369D02*
X713622Y-232393D01*
X712094Y-231227D01*
X710784Y-229477D01*
X709910Y-227435D01*
X709474Y-225102D01*
Y-222768D01*
X709910Y-220435D01*
X710784Y-218393D01*
X712094Y-216644D01*
X713622Y-215477D01*
X715369Y-215185D01*
X717115Y-215477D01*
X718644Y-216644D01*
X719954Y-218393D01*
X720828Y-220435D01*
X721264Y-222768D01*
Y-225102D01*
X720828Y-227435D01*
X719954Y-229477D01*
X718644Y-231227D01*
X717115Y-232393D01*
X715369Y-232685D01*
G01X794069Y-215185D02*
X792322Y-215768D01*
X791012Y-217227D01*
X790139Y-218976D01*
X789484Y-221310D01*
X789266Y-223935D01*
X789484Y-226560D01*
X790139Y-228894D01*
X791012Y-230644D01*
X792322Y-232102D01*
X794069Y-232685D01*
X795815Y-232102D01*
X797126Y-230644D01*
X797999Y-228894D01*
X798654Y-226560D01*
X798872Y-223935D01*
X798654Y-221310D01*
X797999Y-218976D01*
X797126Y-217227D01*
X795815Y-215768D01*
X794069Y-215185D01*
G01X807421Y-225394D02*
X808949Y-223352D01*
X810259Y-222185D01*
X812006Y-221602D01*
X813534Y-222185D01*
X814626Y-223352D01*
X815499Y-225102D01*
X815717Y-227143D01*
X815499Y-228894D01*
X814626Y-230644D01*
X813315Y-232102D01*
X811787Y-232685D01*
X810041Y-232102D01*
X808512Y-230352D01*
X807639Y-227727D01*
X807421Y-224810D01*
X807857Y-221019D01*
X808512Y-218976D01*
X809604Y-216935D01*
X811132Y-215477D01*
X812661Y-215185D01*
X814189Y-215768D01*
X815281Y-217227D01*
G01X825139Y-233268D02*
X832999Y-215185D01*
G01X842421Y-218102D02*
X843731Y-216352D01*
X845259Y-215477D01*
X847006Y-215185D01*
X849189Y-215768D01*
X850717Y-217227D01*
X851154Y-218976D01*
X850936Y-220727D01*
X850062Y-222185D01*
X845696Y-225102D01*
X843731Y-227143D01*
X842421Y-230061D01*
X841984Y-232685D01*
X851154D01*
G01X859921Y-218102D02*
X861231Y-216352D01*
X862759Y-215477D01*
X864506Y-215185D01*
X866689Y-215768D01*
X868217Y-217227D01*
X868654Y-218976D01*
X868436Y-220727D01*
X867562Y-222185D01*
X863196Y-225102D01*
X861231Y-227143D01*
X859921Y-230061D01*
X859484Y-232685D01*
X868654D01*
G01X877639Y-233268D02*
X885499Y-215185D01*
G01X894921Y-218102D02*
X896231Y-216352D01*
X897759Y-215477D01*
X899506Y-215185D01*
X901689Y-215768D01*
X903217Y-217227D01*
X903654Y-218976D01*
X903436Y-220727D01*
X902562Y-222185D01*
X898196Y-225102D01*
X896231Y-227143D01*
X894921Y-230061D01*
X894484Y-232685D01*
X903654D01*
G01X916569Y-215185D02*
X914822Y-215768D01*
X913512Y-217227D01*
X912639Y-218976D01*
X911984Y-221310D01*
X911766Y-223935D01*
X911984Y-226560D01*
X912639Y-228894D01*
X913512Y-230644D01*
X914822Y-232102D01*
X916569Y-232685D01*
X918315Y-232102D01*
X919626Y-230644D01*
X920499Y-228894D01*
X921154Y-226560D01*
X921372Y-223935D01*
X921154Y-221310D01*
X920499Y-218976D01*
X919626Y-217227D01*
X918315Y-215768D01*
X916569Y-215185D01*
G01X934069Y-232685D02*
Y-215185D01*
X931449Y-218685D01*
G01Y-232685D02*
X936689D01*
G01X951132D02*
X951569Y-228894D01*
X952224Y-225685D01*
X953097Y-222768D01*
X954189Y-219560D01*
X955936Y-215185D01*
X947202D01*
G01X841766Y-187685D02*
Y-170185D01*
X846132D01*
X847879Y-171060D01*
X849189Y-172227D01*
X850281Y-173976D01*
X851154Y-176019D01*
X851372Y-178935D01*
X851154Y-181852D01*
X850281Y-183894D01*
X849189Y-185644D01*
X847879Y-186810D01*
X846132Y-187685D01*
X841766D01*
G01X867999D02*
Y-176019D01*
G01Y-178060D02*
X867126Y-176894D01*
X865815Y-176310D01*
X864287Y-176019D01*
X862759Y-176602D01*
X861449Y-177768D01*
X860575Y-179518D01*
X860139Y-181852D01*
X860575Y-184185D01*
X861449Y-185935D01*
X862759Y-187102D01*
X864287Y-187685D01*
X865815Y-187393D01*
X867126Y-186519D01*
X867999Y-185352D01*
G01X881569Y-170185D02*
Y-187685D01*
G01X878512Y-176019D02*
X884626D01*
G01X895794Y-179810D02*
X902781D01*
X902126Y-177768D01*
X901034Y-176602D01*
X899506Y-176019D01*
X897977Y-176310D01*
X896667Y-177185D01*
X895794Y-179227D01*
X895357Y-180977D01*
Y-182727D01*
X895794Y-184477D01*
X896886Y-186227D01*
X898196Y-187393D01*
X899724Y-187685D01*
X901252Y-187102D01*
X902781Y-185352D01*
G01X-25590Y9843D02*
G03X-15748Y0I9842J-1D01*
G01X-25590Y89370D02*
Y9843D01*
G01X-23622Y91339D02*
G03X-25590Y89370I1J-1969D01*
G01X-7874Y91339D02*
X-23622D01*
G01X-25590Y109055D02*
G03X-21653Y105118I3937J0D01*
G01X-25590Y357874D02*
Y109055D01*
G01X-21653Y105118D02*
X261811D01*
G01X-25590Y371654D02*
G03X-23622Y369685I1968J-1D01*
G01X-21653Y361811D02*
G03X-25590Y357874I0J-3937D01*
G01X1969Y361811D02*
X-21653D01*
G01X-7874Y369685D02*
X-23622D01*
G01X-25590Y459055D02*
Y371654D01*
G01X-23622Y461024D02*
G03X-25590Y459055I1J-1969D01*
G01X-7874Y461024D02*
X-23622D01*
G01X-25590Y478740D02*
G03X-21653Y474803I3937J0D01*
G01X-25590Y727559D02*
Y478740D01*
G01X-21653Y474803D02*
X261811D01*
G01X-21653Y731496D02*
G03X-25590Y727559I0J-3937D01*
G01X1969Y731496D02*
X-21653D01*
G01X-11811Y0D02*
G03X-7874Y3937I0J3937D01*
G01X-11811Y0D02*
X-15748D01*
G01X0Y3937D02*
G03X3937Y0I3937J0D01*
G01X-7874Y33071D02*
Y3937D01*
G01X0Y87402D02*
Y3937D01*
G01Y33071D02*
G03X-7874I-3937J0D01*
G01Y58268D02*
G03X0I3937J0D01*
G01X-7874Y91339D02*
Y58268D01*
G01X3937Y91339D02*
G03X0Y87402I0J-3937D01*
G01X5906Y357874D02*
G03X1969Y361811I-3937J0D01*
G01X0Y373622D02*
G03X3937Y369685I3937J0D01*
G01X-7874Y402756D02*
Y369685D01*
G01X0Y457087D02*
Y373622D01*
G01Y402756D02*
G03X-7874I-3937J0D01*
G01Y427953D02*
G03X0I3937J0D01*
G01X-7874Y461024D02*
Y427953D01*
G01X3937Y461024D02*
G03X0Y457087I0J-3937D01*
G01X5906Y727559D02*
G03X1969Y731496I-3937J0D01*
G01X3937Y0D02*
X372048D01*
G01X192914Y91339D02*
X3937D01*
G01X5906Y290748D02*
G03X9843Y286811I3937J0D01*
G01X5906Y357874D02*
Y290748D01*
G01X69488Y286811D02*
X9843D01*
G01X13780Y315650D02*
Y294685D01*
G01X69488D02*
X13780D01*
G01Y315650D02*
G03X5906I-3937J0D01*
G01Y340847D02*
G03X13780I3937J0D01*
G01Y361811D02*
Y340847D01*
G01X3937Y369685D02*
X372048D01*
G01X43307Y361811D02*
X13780D01*
G01X192914Y461024D02*
X3937D01*
G01X5906Y660433D02*
G03X9843Y656496I3937J0D01*
G01X5906Y727559D02*
Y660433D01*
G01X69488Y656496D02*
X9843D01*
G01X13780Y685335D02*
Y664370D01*
G01X69488D02*
X13780D01*
G01Y685335D02*
G03X5906I-3937J0D01*
G01Y710532D02*
G03X13780I3937J0D01*
G01Y729528D02*
Y710532D01*
G01X15748Y731496D02*
G03X13780Y729528I0J-1968D01*
G01X44819Y731496D02*
X15748D01*
G01X43307Y361811D02*
G03Y369685I0J3937D01*
G01X46675Y730184D02*
G03X44819Y731496I-1856J-657D01*
G01X46675Y730184D02*
G03X54098I3712J1313D01*
G01X53150Y181697D02*
G03X55118Y179729I1968J0D01*
G01X53150Y195477D02*
Y181697D01*
G01X55118Y179729D02*
X161418D01*
G01X55118Y197445D02*
G03X53150Y195477I0J-1968D01*
G01X161418Y197445D02*
X55118D01*
G01X73426Y282874D02*
G03X69488Y286811I-3937J0D01*
G01X81300Y282874D02*
G03X69488Y294685I-11811J0D01*
G01X74016Y369685D02*
G03Y361811I0J-3937D01*
G01X53150Y551382D02*
G03X55118Y549414I1968J0D01*
G01X53150Y565162D02*
Y551382D01*
G01X55118Y549414D02*
X161418D01*
G01X55118Y567130D02*
G03X53150Y565162I0J-1968D01*
G01X161418Y567130D02*
X55118D01*
G01X73426Y652559D02*
G03X69488Y656496I-3937J0D01*
G01X81300Y652559D02*
G03X69488Y664370I-11811J0D01*
G01X55954Y731496D02*
G03X54098Y730184I0J-1969D01*
G01X153544Y731496D02*
X55954D01*
G01X80709Y43307D02*
G03X82677Y41339I1968J0D01*
G01Y47244D02*
G03X80709Y45276I0J-1968D01*
G01X188977Y47244D02*
X82677D01*
G01Y41339D02*
X188977D01*
G01X80709Y45276D02*
Y43307D01*
G01X86614Y101181D02*
G03X82677Y105118I-3937J0D01*
G01X86614Y95276D02*
Y101181D01*
G01X82677Y91339D02*
G03X86614Y95276I0J3937D01*
G01X73426Y267323D02*
G03X77363Y263386I3937J0D01*
G01X73426Y267323D02*
Y282874D01*
G01X77363Y263386D02*
X159449D01*
G01X81300Y271260D02*
Y282874D01*
G01Y271260D02*
X155512D01*
G01Y361811D02*
X74016D01*
G01X80709Y412992D02*
G03X82677Y411024I1968J0D01*
G01Y416929D02*
G03X80709Y414961I0J-1968D01*
G01X188977Y416929D02*
X82677D01*
G01Y411024D02*
X188977D01*
G01X80709Y414961D02*
Y412992D01*
G01X86614Y464961D02*
Y470866D01*
G01X82677Y461024D02*
G03X86614Y464961I0J3937D01*
G01Y470866D02*
G03X82677Y474803I-3937J0D01*
G01X73426Y637008D02*
G03X77363Y633071I3937J0D01*
G01X73426Y637008D02*
Y652559D01*
G01X77363Y633071D02*
X159449D01*
G01X81300Y640945D02*
Y652559D01*
G01Y640945D02*
X155512D01*
G01X109449Y95276D02*
Y101181D01*
G01X113386Y105118D02*
G03X109449Y101181I0J-3937D01*
G01Y95276D02*
G03X113386Y91339I3937J0D01*
G01X109449Y464961D02*
Y470866D01*
G01Y464961D02*
G03X113386Y461024I3937J0D01*
G01Y474803D02*
G03X109449Y470866I0J-3937D01*
G01X161418Y179729D02*
G03X163386Y181697I0J1968D01*
G01Y195477D02*
G03X161418Y197445I-1968J0D01*
G01X159449Y263386D02*
G03X163386Y267323I0J3937D01*
G01X155512Y303937D02*
Y271260D01*
G01X163386Y303937D02*
G03X155512I-3937J0D01*
G01Y329134D02*
G03X163386I3937J0D01*
G01X155512Y361811D02*
Y329134D01*
G01X161418Y549414D02*
G03X163386Y551382I0J1968D01*
G01Y565162D02*
G03X161418Y567130I-1968J0D01*
G01X159449Y633071D02*
G03X163386Y637008I0J3937D01*
G01X155512Y673622D02*
Y640945D01*
G01X163386Y673622D02*
G03X155512I-3937J0D01*
G01Y698819D02*
G03X163386I3937J0D01*
G01X155512Y729528D02*
Y698819D01*
G01Y729528D02*
G03X153544Y731496I-1968J0D01*
G01X163386Y181697D02*
Y195477D01*
G01Y357874D02*
Y267323D01*
G01X167323Y361811D02*
G03X163386Y357874I0J-3937D01*
G01X535433Y361811D02*
X167323D01*
G01X163386Y551382D02*
Y565162D01*
G01Y727559D02*
Y637008D01*
G01X167323Y731496D02*
G03X163386Y727559I0J-3937D01*
G01X535433Y731496D02*
X167323D01*
G01X188977Y41339D02*
G03X190945Y43307I0J1968D01*
G01Y45276D02*
G03X188977Y47244I-1968J0D01*
G01X190945Y43307D02*
Y45276D01*
G01X196851Y97244D02*
G03X194882Y95276I0J-1969D01*
G01X192914Y91339D02*
G03X194882Y93307I0J1968D01*
G01X196851Y97244D02*
X269685D01*
G01X194882Y93307D02*
Y95276D01*
G01X188977Y411024D02*
G03X190945Y412992I0J1968D01*
G01Y414961D02*
G03X188977Y416929I-1968J0D01*
G01X190945Y412992D02*
Y414961D01*
G01X196851Y466929D02*
G03X194882Y464961I-1J-1968D01*
G01X192914Y461024D02*
G03X194882Y462992I0J1968D01*
G01D02*
Y464961D01*
G01X196851Y466929D02*
X269685D01*
G01Y97244D02*
G03X273622Y101181I0J3937D01*
G01Y252756D02*
Y101181D01*
G01X261811Y105118D02*
G03X265748Y109055I0J3937D01*
G01D02*
Y260630D01*
G01X273622Y165551D02*
G03X265748I-3937J0D01*
G01Y196260D02*
G03X273622I3937J0D01*
G01X269685Y264567D02*
G03X265748Y260630I0J-3937D01*
G01X277559Y256693D02*
G03X273622Y252756I0J-3937D01*
G01X342520Y264567D02*
X269685D01*
G01X254331Y361811D02*
G03Y369685I0J3937D01*
G01X261811Y474803D02*
G03X265748Y478740I0J3937D01*
G01D02*
Y630315D01*
G01X269685Y466929D02*
G03X273622Y470866I0J3937D01*
G01Y622441D02*
Y470866D01*
G01Y535236D02*
G03X265748I-3937J0D01*
G01Y565945D02*
G03X273622I3937J0D01*
G01X277559Y626378D02*
G03X273622Y622441I0J-3937D01*
G01X269685Y634252D02*
G03X265748Y630315I0J-3937D01*
G01X342520Y634252D02*
X269685D01*
G01X561024Y256693D02*
X277559D01*
G01X285040Y369685D02*
G03Y361811I0J-3937D01*
G01X561024Y626378D02*
X277559D01*
G01X342520Y264567D02*
G03X344488Y266536I0J1968D01*
G01X342520Y634252D02*
G03X344488Y636221I0J1968D01*
G01X346457Y270473D02*
G03X344488Y268504I0J-1969D01*
G01X346457Y270473D02*
X535433D01*
G01X344488Y268504D02*
Y266536D01*
G01X350394Y320473D02*
G03X348426Y318504I0J-1968D01*
G01Y316536D02*
G03X350394Y314567I1968J-1D01*
G01D02*
X456693D01*
G01Y320473D02*
X350394D01*
G01X348426Y318504D02*
Y316536D01*
G01X346457Y640158D02*
G03X344488Y638189I0J-1969D01*
G01X346457Y640158D02*
X535433D01*
G01X344488Y638189D02*
Y636221D01*
G01X350394Y690158D02*
G03X348426Y688189I0J-1968D01*
G01Y686221D02*
G03X350394Y684252I1968J-1D01*
G01D02*
X456693D01*
G01Y690158D02*
X350394D01*
G01X348426Y688189D02*
Y686221D01*
G01X383859Y1969D02*
G03X385827Y0I1968J-1D01*
G01D02*
X523622D01*
G01X372048D02*
G03X375985Y3937I0J3937D01*
G01X383859Y1969D02*
Y32677D01*
G01X375985Y3937D02*
Y94488D01*
G01X383859Y32677D02*
G03X375985I-3937J0D01*
G01Y57874D02*
G03X383859I3937J0D01*
G01D02*
Y90551D01*
G01X379922Y98425D02*
G03X375985Y94488I0J-3937D01*
G01X458071Y90551D02*
X383859D01*
G01X462008Y98425D02*
X379922D01*
G01X375985Y166334D02*
G03X377953Y164365I1969J0D01*
G01X375985Y180113D02*
Y166334D01*
G01X377953Y164365D02*
X484252D01*
G01X377953Y182082D02*
G03X375985Y180113I0J-1968D01*
G01X484252Y182082D02*
X377953D01*
G01X383859Y369685D02*
X465355D01*
G01X372048D02*
G03X375985Y373622I0J3937D01*
G01X383859Y369685D02*
Y402362D01*
G01X375985Y373622D02*
Y464173D01*
G01X383859Y402362D02*
G03X375985I-3937J0D01*
G01Y427559D02*
G03X383859I3937J0D01*
G01D02*
Y460236D01*
G01X379922Y468110D02*
G03X375985Y464173I0J-3937D01*
G01X458071Y460236D02*
X383859D01*
G01X462008Y468110D02*
X379922D01*
G01X375985Y536019D02*
G03X377953Y534050I1969J0D01*
G01D02*
X484252D01*
G01X377953Y551767D02*
G03X375985Y549799I0J-1968D01*
G01D02*
Y536019D01*
G01X484252Y551767D02*
X377953D01*
G01X429922Y260630D02*
Y266536D01*
G01X425985Y256693D02*
G03X429922Y260630I0J3937D01*
G01Y266536D02*
G03X425985Y270473I-3937J0D01*
G01X429922Y630315D02*
Y636221D01*
G01X425985Y626378D02*
G03X429922Y630315I0J3937D01*
G01Y636221D02*
G03X425985Y640158I-3937J0D01*
G01X452756Y260630D02*
G03X456693Y256693I3937J0D01*
G01X452756Y260630D02*
Y266536D01*
G01X456693Y270473D02*
G03X452756Y266536I0J-3937D01*
G01X458662Y318504D02*
G03X456693Y320473I-1969J0D01*
G01Y314567D02*
G03X458662Y316536I0J1969D01*
G01X452756Y630315D02*
G03X456693Y626378I3937J0D01*
G01X452756Y630315D02*
Y636221D01*
G01X456693Y640158D02*
G03X452756Y636221I0J-3937D01*
G01X458662Y688189D02*
G03X456693Y690158I-1969J0D01*
G01Y684252D02*
G03X458662Y686221I0J1969D01*
G01X458071Y78937D02*
G03X469882Y67126I11811J0D01*
G01X465945Y78937D02*
G03X469882Y75000I3937J0D01*
G01X458071Y90551D02*
Y78937D01*
G01X465945Y94488D02*
Y78937D01*
G01X469882Y67126D02*
X525591D01*
G01X469882Y75000D02*
X529528D01*
G01X465945Y94488D02*
G03X462008Y98425I-3937J0D01*
G01X458662Y316536D02*
Y318504D01*
G01X465355Y361811D02*
G03Y369685I0J3937D01*
G01X458071Y448622D02*
G03X469882Y436811I11811J0D01*
G01D02*
X525591D01*
G01X465945Y448622D02*
G03X469882Y444685I3937J0D01*
G01X465945Y464173D02*
G03X462008Y468110I-3937J0D01*
G01X458071Y460236D02*
Y448622D01*
G01X465945Y464173D02*
Y448622D01*
G01X469882Y444685D02*
X529528D01*
G01X458662Y686221D02*
Y688189D01*
G01X484252Y164365D02*
G03X486221Y166334I0J1969D01*
G01D02*
Y180113D01*
G01D02*
G03X484252Y182082I-1969J0D01*
G01X496063Y369685D02*
G03Y361811I0J-3937D01*
G01Y369685D02*
X525591D01*
G01X484252Y534050D02*
G03X486221Y536019I0J1969D01*
G01Y549799D02*
G03X484252Y551767I-1969J-1D01*
G01X486221Y536019D02*
Y549799D01*
G01X523622Y0D02*
G03X525591Y1969I0J1969D01*
G01X533465Y3937D02*
G03X537402Y0I3937J0D01*
G01X525591Y1969D02*
Y20965D01*
G01X533465Y3937D02*
Y71063D01*
G01X537402Y0D02*
X561024D01*
G01X533465Y20965D02*
G03X525591I-3937J0D01*
G01Y46162D02*
G03X533465I3937J0D01*
G01X525591D02*
Y67126D01*
G01X533465Y71063D02*
G03X529528Y75000I-3937J0D01*
G01X535433Y270473D02*
G03X539370Y274410I0J3937D01*
G01D02*
Y357874D01*
G01X547244Y270473D02*
X562992D01*
G01X547244D02*
Y303543D01*
G01D02*
G03X539370I-3937J0D01*
G01Y328740D02*
G03X547244I3937J0D01*
G01D02*
Y361811D01*
G01X539370Y357874D02*
G03X535433Y361811I-3937J0D01*
G01X547244D02*
X562992D01*
G01X533465Y373622D02*
G03X537402Y369685I3937J0D01*
G01X525591D02*
Y390650D01*
G01X533465Y373622D02*
Y440748D01*
G01X537402Y369685D02*
X561024D01*
G01X533465Y390650D02*
G03X525591I-3937J0D01*
G01Y415847D02*
G03X533465I3937J0D01*
G01X525591D02*
Y436811D01*
G01X533465Y440748D02*
G03X529528Y444685I-3937J0D01*
G01X535433Y640158D02*
G03X539370Y644095I0J3937D01*
G01D02*
Y727559D01*
G01X547244Y640158D02*
X562992D01*
G01X547244D02*
Y673228D01*
G01D02*
G03X539370I-3937J0D01*
G01Y698425D02*
G03X547244I3937J0D01*
G01D02*
Y727559D01*
G01X551181Y731496D02*
G03X547244Y727559I0J-3937D01*
G01X539370D02*
G03X535433Y731496I-3937J0D01*
G01X561024Y0D02*
G03X564961Y3937I0J3937D01*
G01D02*
Y252756D01*
G01D02*
G03X561024Y256693I-3937J0D01*
G01X562992Y270473D02*
G03X564961Y272441I1J1968D01*
G01D02*
Y359843D01*
G01D02*
G03X562992Y361811I-1968J0D01*
G01X561024Y369685D02*
G03X564961Y373622I0J3937D01*
G01D02*
Y622441D01*
G01D02*
G03X561024Y626378I-3937J0D01*
G01X562992Y640158D02*
G03X564961Y642126I1J1968D01*
G01D02*
Y721654D01*
G01D02*
G03X555118Y731496I-9842J0D01*
G01X551181D02*
X555118D01*
G54D14*
X182700Y75000D03*
X186900Y32100D03*
X220920Y33897D03*
X216594Y74962D03*
X464035Y224263D03*
X488700Y158300D03*
X491846Y224052D03*
X511700Y158500D03*
G54D23*
X228630Y76864D03*
Y85564D03*
X244456Y33299D03*
X233456D03*
X244456Y41999D03*
X233456D03*
X239630Y76864D03*
Y85564D03*
X289800Y150000D03*
X300800D03*
X289800Y158700D03*
X300800D03*
G54D15*
X198356Y33399D03*
X205956D03*
X194830Y76364D03*
X202430D03*
X266292Y48559D03*
X273892D03*
X309800Y192500D03*
X302200D03*
X322966Y199919D03*
X309800Y200500D03*
X302200D03*
X337012Y44327D03*
X344612D03*
X324686Y162130D03*
X332286D03*
X330566Y199919D03*
G54D24*
X267148Y39395D03*
X271238Y67208D03*
X310500Y152000D03*
X321777Y191293D03*
X336921Y51884D03*
G54D25*
X316700Y32000D03*
X308700D03*
X321200Y142000D03*
X309200Y133500D03*
X339700Y20000D03*
X328700Y142000D03*
X352200Y29500D03*
X360200D03*
G54D16*
X192500Y32100D03*
X188300Y75000D03*
X226520Y33897D03*
X222194Y74962D03*
X469635Y224263D03*
X494300Y158300D03*
X497446Y224052D03*
X517300Y158500D03*
G54D26*
X313300Y32000D03*
X305300D03*
X317800Y142000D03*
X305800Y133500D03*
X336300Y20000D03*
X325300Y142000D03*
X348800Y29500D03*
X356800D03*
G54D17*
X200674Y38941D03*
X196830Y81864D03*
G54D18*
X204274Y38941D03*
X200430Y81864D03*
G54D27*
X327151Y153540D03*
X357000Y41200D03*
G54D19*
X207500Y74700D03*
X211100Y32000D03*
X320946Y42829D03*
X324423Y42824D03*
X479900Y223700D03*
X502868Y159486D03*
G54D28*
X327151Y150140D03*
X357000Y37800D03*
G54D29*
X331151Y153640D03*
X361000Y41300D03*
M02*
